FILE_TYPE = CONNECTIVITY;
{Allegro Design Entry HDL 17.4-2019 S026 (4007227) 1/17/2022}
"PAGE_NUMBER" = 190;
0"NC";
1"GND\g";
2"GND\g";
3"GND\g";
4"GND\g";
5"GND\g";
6"GND\g";
7"GND\g";
8"GND\g";
9"GND\g";
10"GND\g";
11"GND\g";
12"PVDDCR_CPU0_P1_VCCS";
13"PVDDCR_SOC_P1_IMON2";
14"PVDDCR_SOC_P1_VCC2";
15"GND\g";
16"SW_P12V_AUX_PVDDCR_SOC_P1_FLT\g";
17"PVDDCR_SOC_P1_VOS1";
18"SW_PVDDCR_SOC_P1_SW1";
19"SW_PVDDCR_SOC_P1_PH1";
20"SW_PVDDCR_SOC_P1_BOOT1";
21"SW_PVDDCR_SOC_P1_BOOT1_RC";
22"PVDDCR_SOC_P1_VCC1";
23"SW_PVDDCR_SOC_P1_BOOT2";
24"SW_PVDDCR_SOC_P1_BOOT2_RC";
25"PVDDCR_SOC_P1\g";
26"GND\g";
27"GND\g";
28"SW_P12V_AUX_PVDDCR_SOC_P1_FLT\g";
29"GND\g";
30"P12V_AUX\g";
31"PVDDCR_SOC_P1\g";
32"GND\g";
33"PVDDCR_SOC_P1\g";
34"GND\g";
35"PVDDCR_CPU0_P1_PVCC\g";
36"GND\g";
37"GND\g";
38"PVDDCR_CPU0_P1_PVCC\g";
39"PVDDCR_SOC_P1_PWM1";
40"NC_PVDDCR_SOC_P1_GL1_1";
41"SW_PVDDCR_SOC_P1_SW2";
42"SW_PVDDCR_SOC_P1_PH2";
43"IND_SOC_P1_CPL2";
44"PVDDCR_SOC_P1_PWM2";
45"PVDDCR_SOC_P1_VOS2";
46"IND_SOC_P1_CPL2";
47"IND_SOC_P1_CPL3";
48"SW_PVDDCR_SOC_P1_SW1_RC";
49"NC_PVDDCR_SOC_P1_GL2_1";
50"PVDDCR_SOC_P1_IMON1";
51"PVDDCR_SOC_P1_TEMP1";
52"PVDDCR_SOC_P1_LSET1";
53"NC_PVDDCR_SOC_P1_DNC1";
54"PVDDCR_CPU0_P1_VCCS";
55"SW_PVDDCR_SOC_P1_SW2_RC";
56"NC_PVDDCR_SOC_P1_GL1_2";
57"NC_PVDDCR_SOC_P1_GL2_2";
58"NC_PVDDCR_SOC_P1_DNC2";
59"PVDDCR_SOC_P1_LSET2";
60"PVDDCR_SOC_P1_TEMP1";
%"UNIVERSAL_GND"
"1","(-7525,2125)","0","pure_quanta_power","I10";
;
CDS_LIB"pure_quanta_power"
HDL_POWER"GND";
"A"1;
%"Q_CAP"
"1","(-7525,2325)","0","pure_quanta","I11";
;
LOCATION"PC320"
$SEC"1"
CDS_SEC"1"
VALUE"2.2UF"
PACK_TYPE"C0402"
VOLTAGE"10V"
TOLERANCE"10%"
MATERIAL"X6S"
CDS_LIB"pure_quanta"
PART_NUMBER"CH5222KEB01";
"B"
$PN"2"1;
"A"
$PN"1"14;
%"Q_RES"
"2","(-7525,2875)","0","pure_quanta","I12";
;
LOCATION"PR206"
$SEC"1"
CDS_SEC"1"
PACK_TYPE"0402LF"
WATTAGE"1/16W"
MATERIAL"CHIP"
TOLERANCE"1%"
VALUE"2.2"
CDS_LIB"pure_quanta"
PART_NUMBER"CS-2202FB01";
"A"
$PN"1"38;
"B"
$PN"2"14;
%"VCC_CORE"
"1","(-7525,3275)","0","pure_quanta_power","I13";
;
HDL_POWER"PVDDCR_CPU0_P1_PVCC"
CDS_LIB"pure_quanta_power";
"A"38;
%"Q_CAP"
"1","(-7175,2900)","0","pure_quanta","I14";
;
LOCATION"PC322_SOP1_2"
$SEC"1"
CDS_SEC"1"
PACK_TYPE"C0402"
VOLTAGE"10V"
VALUE"2.2UF"
TOLERANCE"10%"
MATERIAL"X6S"
CDS_LIB"pure_quanta"
PART_NUMBER"CH5222KEB01";
"B"
$PN"2"2;
"A"
$PN"1"38;
%"UNIVERSAL_GND"
"1","(-7175,2625)","0","pure_quanta_power","I15";
;
CDS_LIB"pure_quanta_power"
HDL_POWER"GND";
"A"2;
%"ISL99390FRZTR5935"
"1","(-6050,4750)","0","pure_quanta","I17";
;
LOCATION"PU30"
$SEC"1"
CDS_SEC"1"
PART_TYPE"SMLF"
MATERIAL"IC"
VALUE"ISL99390FRZ-TR5935"
NEEDS_NO_SIZE"TRUE"
CDS_LMAN_SYM_OUTLINE"-300,700,250,-650"
CDS_LIB"pure_quanta"
PART_NUMBER"AL099390004";
"PGND2"
$PN"7_9-20_24"36;
"GL2"
$PN"41"49;
"GL1"
$PN"6"40;
"DNC"
$PN"31"53;
"EN"
$PN"35"22;
"PGND3"
$PN"40"36;
"VOS"
$PN"1"17;
"VIN2"
$PN"30"28;
"PGND1"
$PN"5"36;
"SW"
$PN"10_19"18;
"LSET"
$PN"37"52;
"IOUT"
$PN"38"50;
"TOUT_FLT"
$PN"36"51;
"PVCC"
$PN"4"35;
"PHASE"
$PN"32"19;
"VIN1"
$PN"25_29"28;
"BOOT"
$PN"33"20;
"AGND"
$PN"2"36;
"VCC"
$PN"3"22;
"REFIN"
$PN"39"54;
"PWM"
$PN"34"39;
%"UNIVERSAL_GND"
"1","(-5450,1275)","0","pure_quanta_power","I18";
;
CDS_LIB"pure_quanta_power"
HDL_POWER"GND";
"A"37;
%"UNIVERSAL_GND"
"1","(-4625,1000)","0","pure_quanta_power","I19";
;
CDS_LIB"pure_quanta_power"
HDL_POWER"GND";
"A"3;
%"Q_CAP"
"1","(-4625,1775)","0","pure_quanta","I20";
;
LOCATION"PC149"
$SEC"1"
CDS_SEC"1"
PACK_TYPE"C0402"
VOLTAGE"50V"
VALUE"560PF"
TOLERANCE"10%"
MATERIAL"EMPTY"
CDS_LIB"pure_quanta"
PART_NUMBER"CH1566K1B09";
"B"
$PN"2"55;
"A"
$PN"1"41;
%"Q_RES"
"2","(-4625,1225)","0","pure_quanta","I21";
;
LOCATION"PR526"
$SEC"1"
CDS_SEC"1"
PACK_TYPE"0402LF"
VALUE"1.5"
TOLERANCE"1%"
MATERIAL"EMPTY"
WATTAGE"1/8W"
CDS_LIB"pure_quanta"
PART_NUMBER"CS-1504FB00";
"A"
$PN"1"55;
"B"
$PN"2"3;
%"Q_CAP"
"1","(-5375,2875)","0","pure_quanta","I22";
;
LOCATION"PC326_2"
$SEC"1"
CDS_SEC"1"
VALUE"0.1UF"
VOLTAGE"25V"
PACK_TYPE"0402"
TOLERANCE"10%"
MATERIAL"X7R"
CDS_LIB"pure_quanta"
PART_NUMBER"CH4104K1B00";
"B"
$PN"2"15;
"A"
$PN"1"16;
%"UNIVERSAL_GND"
"1","(-5475,4025)","0","pure_quanta_power","I23";
;
CDS_LIB"pure_quanta_power"
HDL_POWER"GND";
"A"36;
%"Q_RES"
"1","(-4700,2325)","0","pure_quanta","I24";
;
LOCATION"PR210"
$SEC"1"
CDS_SEC"1"
WATTAGE"1/16W"
PACK_TYPE"0402LF"
MATERIAL"CHIP"
TOLERANCE"1%"
VALUE"5.6"
CDS_LIB"pure_quanta"
PART_NUMBER"CS-5602FB01";
"B"
$PN"2"24;
"A"
$PN"1"23;
%"Q_CAP"
"1","(-5000,2875)","0","pure_quanta","I25";
;
LOCATION"PC324_2"
$SEC"1"
CDS_SEC"1"
VOLTAGE"25V"
PACK_TYPE"C0402"
VALUE"1UF"
MATERIAL"X6S"
TOLERANCE"10%"
CDS_LIB"pure_quanta"
PART_NUMBER"CH5104KEB02";
"B"
$PN"2"15;
"A"
$PN"1"16;
%"Q_CAP"
"1","(-4675,2875)","0","pure_quanta","I26";
;
LOCATION"PC328_2"
$SEC"1"
CDS_SEC"1"
MATERIAL"X6S"
TOLERANCE"20%"
PACK_TYPE"C0805"
VOLTAGE"16V"
VALUE"22UF"
CDS_LIB"pure_quanta"
PART_NUMBER"CH6223MEA01";
"B"
$PN"2"15;
"A"
$PN"1"16;
%"Q_CAP"
"1","(-4350,2875)","0","pure_quanta","I27";
;
LOCATION"PC330_2"
$SEC"1"
CDS_SEC"1"
VOLTAGE"16V"
TOLERANCE"20%"
MATERIAL"X6S"
VALUE"22UF"
PACK_TYPE"C0805"
CDS_LIB"pure_quanta"
PART_NUMBER"CH6223MEA01";
"B"
$PN"2"15;
"A"
$PN"1"16;
%"UNIVERSAL_GND"
"1","(-4700,3825)","0","pure_quanta_power","I28";
;
CDS_LIB"pure_quanta_power"
HDL_POWER"GND";
"A"4;
%"Q_RES"
"2","(-4700,4050)","0","pure_quanta","I29";
;
LOCATION"PR525"
$SEC"1"
CDS_SEC"1"
TOLERANCE"1%"
WATTAGE"1/8W"
VALUE"1.5"
MATERIAL"EMPTY"
PACK_TYPE"0402LF"
CDS_LIB"pure_quanta"
PART_NUMBER"CS-1504FB00";
"A"
$PN"1"48;
"B"
$PN"2"4;
%"UNIVERSAL_GND"
"1","(-7850,1425)","0","pure_quanta_power","I3";
;
CDS_LIB"pure_quanta_power"
HDL_POWER"GND";
"A"5;
%"Q_RES"
"1","(-4225,3725)","0","pure_quanta","I30";
;
LOCATION"PR211"
$SEC"1"
CDS_SEC"1"
VALUE"0"
WATTAGE"1/16W"
TOLERANCE"5%"
PACK_TYPE"0402LF"
MATERIAL"CHIP"
CDS_LIB"pure_quanta"
PART_NUMBER"CS00002JB13";
"B"
$PN"2"25;
"A"
$PN"1"17;
%"UNIVERSAL_GND"
"1","(-7875,4200)","0","pure_quanta_power","I31";
;
CDS_LIB"pure_quanta_power"
HDL_POWER"GND";
"A"6;
%"Q_CAP"
"1","(-7875,4475)","0","pure_quanta","I32";
;
LOCATION"PC317_7"
$SEC"1"
CDS_SEC"1"
VALUE"0.1UF"
VOLTAGE"25V"
TOLERANCE"10%"
MATERIAL"X7R"
PACK_TYPE"0402"
CDS_LIB"pure_quanta"
PART_NUMBER"CH4104K1B00";
"B"
$PN"2"6;
"A"
$PN"1"54;
%"UNIVERSAL_GND"
"1","(-7550,4275)","0","pure_quanta_power","I33";
;
CDS_LIB"pure_quanta_power"
HDL_POWER"GND";
"A"7;
%"Q_RES"
"1","(-7200,4450)","0","pure_quanta","I35";
;
LOCATION"PR207"
$SEC"1"
CDS_SEC"1"
WATTAGE"1/16W"
PACK_TYPE"0402LF"
VALUE"8.87K"
TOLERANCE"1%"
MATERIAL"EMPTY"
CDS_LIB"pure_quanta"
PART_NUMBER"CS28872FB01";
"B"
$PN"2"52;
"A"
$PN"1"7;
%"Q_CAP"
"1","(-7550,5100)","0","pure_quanta","I36";
;
LOCATION"PC319"
$SEC"1"
CDS_SEC"1"
VOLTAGE"10V"
PACK_TYPE"C0402"
VALUE"2.2UF"
TOLERANCE"10%"
MATERIAL"X6S"
CDS_LIB"pure_quanta"
PART_NUMBER"CH5222KEB01";
"B"
$PN"2"8;
"A"
$PN"1"22;
%"UNIVERSAL_GND"
"1","(-7550,4900)","0","pure_quanta_power","I37";
;
CDS_LIB"pure_quanta_power"
HDL_POWER"GND";
"A"8;
%"Q_RES"
"2","(-7550,5650)","0","pure_quanta","I39";
;
LOCATION"PR205"
$SEC"1"
CDS_SEC"1"
WATTAGE"1/16W"
MATERIAL"CHIP"
VALUE"2.2"
TOLERANCE"1%"
PACK_TYPE"0402LF"
CDS_LIB"pure_quanta"
PART_NUMBER"CS-2202FB01";
"A"
$PN"1"35;
"B"
$PN"2"22;
%"Q_CAP"
"1","(-7850,1700)","0","pure_quanta","I4";
;
LOCATION"PC318_8"
$SEC"1"
CDS_SEC"1"
PACK_TYPE"0402"
VOLTAGE"25V"
VALUE"0.1UF"
TOLERANCE"10%"
MATERIAL"X7R"
CDS_LIB"pure_quanta"
PART_NUMBER"CH4104K1B00";
"B"
$PN"2"5;
"A"
$PN"1"12;
%"UNIVERSAL_GND"
"1","(-7200,5400)","0","pure_quanta_power","I40";
;
CDS_LIB"pure_quanta_power"
HDL_POWER"GND";
"A"9;
%"Q_CAP"
"1","(-7200,5675)","0","pure_quanta","I41";
;
LOCATION"PC321_SOP1_1"
$SEC"1"
CDS_SEC"1"
TOLERANCE"10%"
VOLTAGE"10V"
PACK_TYPE"C0402"
VALUE"2.2UF"
MATERIAL"X6S"
CDS_LIB"pure_quanta"
PART_NUMBER"CH5222KEB01";
"B"
$PN"2"9;
"A"
$PN"1"35;
%"VCC_CORE"
"1","(-7550,6050)","0","pure_quanta_power","I42";
;
HDL_POWER"PVDDCR_CPU0_P1_PVCC"
CDS_LIB"pure_quanta_power";
"A"35;
%"Q_CAP"
"1","(-5450,5600)","0","pure_quanta","I43";
;
LOCATION"PC325_1"
$SEC"1"
CDS_SEC"1"
MATERIAL"X7R"
PACK_TYPE"0402"
VALUE"0.1UF"
VOLTAGE"25V"
TOLERANCE"10%"
CDS_LIB"pure_quanta"
PART_NUMBER"CH4104K1B00";
"B"
$PN"2"27;
"A"
$PN"1"28;
%"Q_CAP"
"1","(-5125,5600)","0","pure_quanta","I44";
;
LOCATION"PC323_1"
$SEC"1"
CDS_SEC"1"
PACK_TYPE"C0402"
MATERIAL"X6S"
TOLERANCE"10%"
VOLTAGE"25V"
VALUE"1UF"
CDS_LIB"pure_quanta"
PART_NUMBER"CH5104KEB02";
"B"
$PN"2"27;
"A"
$PN"1"28;
%"Q_CAP"
"1","(-4700,4550)","0","pure_quanta","I45";
;
LOCATION"PC141"
$SEC"1"
CDS_SEC"1"
MATERIAL"EMPTY"
PACK_TYPE"C0402"
VOLTAGE"50V"
TOLERANCE"10%"
VALUE"560PF"
CDS_LIB"pure_quanta"
PART_NUMBER"CH1566K1B09";
"B"
$PN"2"48;
"A"
$PN"1"18;
%"Q_RES"
"1","(-4800,5100)","0","pure_quanta","I46";
;
LOCATION"PR209"
$SEC"1"
CDS_SEC"1"
WATTAGE"1/16W"
PACK_TYPE"0402LF"
MATERIAL"CHIP"
TOLERANCE"1%"
VALUE"5.6"
CDS_LIB"pure_quanta"
PART_NUMBER"CS-5602FB01";
"B"
$PN"2"21;
"A"
$PN"1"20;
%"Q_CAP"
"1","(-4800,5600)","0","pure_quanta","I48";
;
LOCATION"PC327_1"
$SEC"1"
CDS_SEC"1"
PACK_TYPE"C0805"
VALUE"22UF"
VOLTAGE"16V"
MATERIAL"X6S"
TOLERANCE"20%"
CDS_LIB"pure_quanta"
PART_NUMBER"CH6223MEA01";
"B"
$PN"2"27;
"A"
$PN"1"28;
%"Q_CAP"
"1","(-4475,5600)","0","pure_quanta","I49";
;
LOCATION"PC329_1"
$SEC"1"
CDS_SEC"1"
TOLERANCE"20%"
VOLTAGE"16V"
PACK_TYPE"C0805"
MATERIAL"X6S"
VALUE"22UF"
CDS_LIB"pure_quanta"
PART_NUMBER"CH6223MEA01";
"B"
$PN"2"27;
"A"
$PN"1"28;
%"UNIVERSAL_GND"
"1","(-7525,1500)","0","pure_quanta_power","I5";
;
CDS_LIB"pure_quanta_power"
HDL_POWER"GND";
"A"10;
%"Q_CAP"
"1","(-4175,5600)","0","pure_quanta","I50";
;
LOCATION"PC331_1"
$SEC"1"
CDS_SEC"1"
VALUE"22UF"
PACK_TYPE"C0805"
VOLTAGE"16V"
TOLERANCE"20%"
MATERIAL"X6S"
CDS_LIB"pure_quanta"
PART_NUMBER"CH6223MEA01";
"B"
$PN"2"27;
"A"
$PN"1"28;
%"Q_INDUCTOR4P_14"
"1","(-2950,1850)","0","pure_quanta","I52";
;
LOCATION"PL36"
$SEC"1"
CDS_SEC"1"
MATERIAL"IND"
PART_TYPE"SMLF"
VALUE"150NH"
NEEDS_NO_SIZE"TRUE"
CDS_LIB"pure_quanta"
PART_NUMBER"CV+15^0TZ04";
"1"
$PN"1"41;
"4"
$PN"4"33;
"3"
$PN"3"46;
"2"
$PN"2"47;
%"Q_CAP"
"1","(-3825,2200)","0","pure_quanta","I54";
;
LOCATION"PC334"
$SEC"1"
CDS_SEC"1"
TOLERANCE"10%"
VALUE"0.22UF"
PACK_TYPE"0402"
VOLTAGE"16V"
MATERIAL"X7R"
CDS_LIB"pure_quanta"
PART_NUMBER"CH4223K1B00";
"B"
$PN"2"42;
"A"
$PN"1"24;
%"UNIVERSAL_GND"
"1","(-3725,2550)","0","pure_quanta_power","I55";
;
CDS_LIB"pure_quanta_power"
HDL_POWER"GND";
"A"15;
%"Q_CAP"
"1","(-4050,2875)","0","pure_quanta","I56";
;
LOCATION"PC332_2"
$SEC"1"
CDS_SEC"1"
TOLERANCE"20%"
VOLTAGE"16V"
VALUE"22UF"
MATERIAL"X6S"
PACK_TYPE"C0805"
CDS_LIB"pure_quanta"
PART_NUMBER"CH6223MEA01";
"B"
$PN"2"15;
"A"
$PN"1"16;
%"Q_CAP"
"1","(-3725,2875)","0","pure_quanta","I57";
;
LOCATION"PC335_2"
$SEC"1"
CDS_SEC"1"
VOLTAGE"16V"
TOLERANCE"20%"
MATERIAL"X6S"
PACK_TYPE"C0805"
VALUE"22UF"
CDS_LIB"pure_quanta"
PART_NUMBER"CH6223MEA01";
"B"
$PN"2"15;
"A"
$PN"1"16;
%"VCC_CORE"
"1","(-3725,3175)","0","pure_quanta_power","I58";
;
HDL_POWER"SW_P12V_AUX_PVDDCR_SOC_P1_FLT"
CDS_LIB"pure_quanta_power";
"A"16;
%"Q_CAPP"
"1","(-2125,3075)","0","pure_quanta","I59";
;
LOCATION"PC337"
$SEC"1"
CDS_SEC"1"
VOLTAGE"2.5V"
VALUE"470UF"
TOLERANCE"20%"
MATERIAL"SPCAP"
PACK_TYPE"SMLF"
CDS_LIB"pure_quanta"
PART_NUMBER"CH747LM8825";
"A"
$PN"1"31;
"B"
$PN"2"32;
%"Q_CAP"
"1","(-1700,1800)","0","pure_quanta","I60";
;
LOCATION"PC339_2"
$SEC"1"
CDS_SEC"1"
PACK_TYPE"C0805"
MATERIAL"X6S"
TOLERANCE"20%"
VALUE"22UF"
VOLTAGE"4V"
CDS_LIB"pure_quanta"
PART_NUMBER"CH622KMEA03";
"B"
$PN"2"34;
"A"
$PN"1"33;
%"UNIVERSAL_GND"
"1","(-1275,1450)","0","pure_quanta_power","I61";
;
CDS_LIB"pure_quanta_power"
HDL_POWER"GND";
"A"34;
%"Q_CAP"
"1","(-1275,1800)","0","pure_quanta","I62";
;
LOCATION"PC342_2"
$SEC"1"
CDS_SEC"1"
PACK_TYPE"C0805"
MATERIAL"X6S"
TOLERANCE"20%"
VALUE"22UF"
VOLTAGE"4V"
CDS_LIB"pure_quanta"
PART_NUMBER"CH622KMEA03";
"B"
$PN"2"34;
"A"
$PN"1"33;
%"Q_CAPP"
"1","(-1775,3075)","0","pure_quanta","I63";
;
LOCATION"PC340"
$SEC"1"
CDS_SEC"1"
PACK_TYPE"SMLF"
VOLTAGE"2.5V"
VALUE"470UF"
TOLERANCE"20%"
MATERIAL"EMPTY"
CDS_LIB"pure_quanta"
PART_NUMBER"CH747LM8825";
"A"
$PN"1"31;
"B"
$PN"2"32;
%"VCC_CORE"
"1","(-1275,2125)","0","pure_quanta_power","I64";
;
HDL_POWER"PVDDCR_SOC_P1"
CDS_LIB"pure_quanta_power";
"A"33;
%"UNIVERSAL_GND"
"1","(-1450,2725)","0","pure_quanta_power","I65";
;
CDS_LIB"pure_quanta_power"
HDL_POWER"GND";
"A"32;
%"Q_CAPP"
"1","(-1450,3075)","0","pure_quanta","I66";
;
LOCATION"PC343"
$SEC"1"
CDS_SEC"1"
VALUE"470UF"
TOLERANCE"20%"
VOLTAGE"2.5V"
MATERIAL"SPCAP"
PACK_TYPE"SMLF"
CDS_LIB"pure_quanta"
PART_NUMBER"CH747LM8825";
"A"
$PN"1"31;
"B"
$PN"2"32;
%"VCC_CORE"
"1","(-1450,3350)","0","pure_quanta_power","I67";
;
HDL_POWER"PVDDCR_SOC_P1"
CDS_LIB"pure_quanta_power";
"A"31;
%"Q_CAP"
"1","(-3950,4975)","0","pure_quanta","I68";
;
LOCATION"PC333"
$SEC"1"
CDS_SEC"1"
PACK_TYPE"0402"
MATERIAL"X7R"
TOLERANCE"10%"
VOLTAGE"16V"
VALUE"0.22UF"
CDS_LIB"pure_quanta"
PART_NUMBER"CH4223K1B00";
"B"
$PN"2"19;
"A"
$PN"1"21;
%"Q_INDUCTOR4P_14"
"1","(-3200,4625)","0","pure_quanta","I69";
;
LOCATION"PL35"
$SEC"1"
CDS_SEC"1"
MATERIAL"IND"
PART_TYPE"SMLF"
VALUE"150NH"
NEEDS_NO_SIZE"TRUE"
CDS_LIB"pure_quanta"
PART_NUMBER"CV+15^0TZ04";
"1"
$PN"1"18;
"4"
$PN"4"25;
"3"
$PN"3"26;
"2"
$PN"2"43;
%"UNIVERSAL_GND"
"1","(-3925,5275)","0","pure_quanta_power","I70";
;
CDS_LIB"pure_quanta_power"
HDL_POWER"GND";
"A"27;
%"Q_CAP"
"1","(-3950,5600)","0","pure_quanta","I71";
;
LOCATION"PC334_1"
$SEC"1"
CDS_SEC"1"
VALUE"22UF"
TOLERANCE"20%"
VOLTAGE"16V"
MATERIAL"X6S"
PACK_TYPE"C0805"
CDS_LIB"pure_quanta"
PART_NUMBER"CH6223MEA01";
"B"
$PN"2"27;
"A"
$PN"1"28;
%"VCC_CORE"
"1","(-3925,5875)","0","pure_quanta_power","I72";
;
HDL_POWER"SW_P12V_AUX_PVDDCR_SOC_P1_FLT"
CDS_LIB"pure_quanta_power";
"A"28;
%"Q_CAPP"
"1","(-3450,5600)","0","pure_quanta","I73";
;
LOCATION"PC336"
$SEC"1"
CDS_SEC"1"
VALUE"270UF"
VOLTAGE"16V"
TOLERANCE"20%"
MATERIAL"OSCON"
PACK_TYPE"THLF"
CDS_LIB"pure_quanta"
PART_NUMBER"CC72703MD38";
"A"
$PN"1"28;
"B"
$PN"2"27;
%"Q_INDUCTOR"
"1","(-3075,5800)","0","pure_quanta","I74";
;
LOCATION"PL37"
$SEC"1"
CDS_SEC"1"
VALUE"50NH/86A"
MATERIAL"IND"
PACK_TYPE"SMLF"
CDS_LIB"pure_quanta"
NEEDS_NO_SIZE"TRUE"
PART_NUMBER"CVA50^0MZ09";
"1"
$PN"1"28;
"2"
$PN"2"30;
%"UNIVERSAL_GND"
"1","(-2325,4375)","0","pure_quanta_power","I75";
;
CDS_LIB"pure_quanta_power"
HDL_POWER"GND";
"A"26;
%"UNIVERSAL_GND"
"1","(-2625,5325)","0","pure_quanta_power","I76";
;
CDS_LIB"pure_quanta_power"
HDL_POWER"GND";
"A"11;
%"Q_CAP"
"1","(-2625,5625)","0","pure_quanta","I77";
;
LOCATION"PC6007"
$SEC"1"
CDS_SEC"1"
MATERIAL"X7R"
VALUE"0.1UF"
PACK_TYPE"0402"
TOLERANCE"10%"
VOLTAGE"25V"
CDS_LIB"pure_quanta"
PART_NUMBER"CH4104K1B00";
"B"
$PN"2"11;
"A"
$PN"1"30;
%"VCC_CORE"
"1","(-2575,5875)","0","pure_quanta_power","I78";
;
HDL_POWER"P12V_AUX"
CDS_LIB"pure_quanta_power";
"A"30;
%"Q_CAP"
"1","(-1975,4550)","0","pure_quanta","I79";
;
LOCATION"PC338"
$SEC"1"
CDS_SEC"1"
PACK_TYPE"0402"
VOLTAGE"25V"
TOLERANCE"10%"
MATERIAL"X7R"
VALUE"0.1UF"
CDS_LIB"pure_quanta"
PART_NUMBER"CH4104K1B00";
"B"
$PN"2"29;
"A"
$PN"1"25;
%"Q_RES"
"1","(-7175,1675)","0","pure_quanta","I8";
;
LOCATION"PR208"
$SEC"1"
CDS_SEC"1"
PACK_TYPE"0402LF"
WATTAGE"1/16W"
VALUE"8.87K"
TOLERANCE"1%"
MATERIAL"EMPTY"
CDS_LIB"pure_quanta"
PART_NUMBER"CS28872FB01";
"B"
$PN"2"59;
"A"
$PN"1"10;
%"Q_CAP"
"1","(-1575,4575)","0","pure_quanta","I80";
;
LOCATION"PC341_1"
$SEC"1"
CDS_SEC"1"
TOLERANCE"20%"
MATERIAL"X6S"
PACK_TYPE"C0805"
VOLTAGE"4V"
VALUE"22UF"
CDS_LIB"pure_quanta"
PART_NUMBER"CH622KMEA03";
"B"
$PN"2"29;
"A"
$PN"1"25;
%"Q_CAP"
"1","(-1150,4575)","0","pure_quanta","I81";
;
LOCATION"PC344_1"
$SEC"1"
CDS_SEC"1"
PACK_TYPE"C0805"
MATERIAL"X6S"
VALUE"22UF"
VOLTAGE"4V"
TOLERANCE"20%"
CDS_LIB"pure_quanta"
PART_NUMBER"CH622KMEA03";
"B"
$PN"2"29;
"A"
$PN"1"25;
%"UNIVERSAL_GND"
"1","(-875,4175)","0","pure_quanta_power","I82";
;
CDS_LIB"pure_quanta_power"
HDL_POWER"GND";
"A"29;
%"Q_RES"
"2","(-875,4550)","0","pure_quanta","I83";
;
LOCATION"PR339"
$SEC"1"
CDS_SEC"1"
PACK_TYPE"0402LF"
MATERIAL"CHIP"
TOLERANCE"1%"
VALUE"1K"
WATTAGE"1/16W"
CDS_LIB"pure_quanta"
PART_NUMBER"CS21002FB06";
"A"
$PN"1"25;
"B"
$PN"2"29;
%"VCC_CORE"
"1","(-875,4875)","0","pure_quanta_power","I84";
;
HDL_POWER"PVDDCR_SOC_P1"
CDS_LIB"pure_quanta_power";
"A"25;
%"Q_RES"
"1","(-4275,800)","0","pure_quanta","I85";
;
LOCATION"PR212"
$SEC"1"
CDS_SEC"1"
VALUE"0"
MATERIAL"CHIP"
WATTAGE"1/16W"
TOLERANCE"5%"
PACK_TYPE"0402LF"
CDS_LIB"pure_quanta"
PART_NUMBER"CS00002JB13";
"B"
$PN"2"33;
"A"
$PN"1"45;
%"ISL99390FRZTR5935"
"1","(-6025,1975)","0","pure_quanta","I86";
;
LOCATION"PU31"
$SEC"1"
CDS_SEC"1"
PART_TYPE"SMLF"
VALUE"ISL99390FRZ-TR5935"
MATERIAL"IC"
CDS_LIB"pure_quanta"
CDS_LMAN_SYM_OUTLINE"-300,700,250,-650"
NEEDS_NO_SIZE"TRUE"
PART_NUMBER"AL099390004";
"PGND2"
$PN"7_9-20_24"37;
"GL2"
$PN"41"57;
"GL1"
$PN"6"56;
"DNC"
$PN"31"58;
"EN"
$PN"35"14;
"PGND3"
$PN"40"37;
"VOS"
$PN"1"45;
"VIN2"
$PN"30"16;
"PGND1"
$PN"5"37;
"SW"
$PN"10_19"41;
"LSET"
$PN"37"59;
"IOUT"
$PN"38"13;
"TOUT_FLT"
$PN"36"60;
"PVCC"
$PN"4"38;
"PHASE"
$PN"32"42;
"VIN1"
$PN"25_29"16;
"BOOT"
$PN"33"23;
"AGND"
$PN"2"37;
"VCC"
$PN"3"14;
"REFIN"
$PN"39"12;
"PWM"
$PN"34"44;
%"Q_CAP"
"1","(-3750,5600)","0","pure_quanta","I87";
;
LOCATION"PC8011"
$SEC"1"
CDS_SEC"1"
TOLERANCE"20%"
VALUE"22UF"
MATERIAL"X6S"
VOLTAGE"16V"
PACK_TYPE"C0805"
CDS_LIB"pure_quanta"
PART_NUMBER"CH6223MEA01";
"B"
$PN"2"27;
"A"
$PN"1"28;
%"Q_CAP"
"1","(-3375,2850)","0","pure_quanta","I88";
;
LOCATION"PC8012"
$SEC"1"
CDS_SEC"1"
PACK_TYPE"C0805"
MATERIAL"X6S"
VOLTAGE"16V"
TOLERANCE"20%"
VALUE"22UF"
CDS_LIB"pure_quanta"
PART_NUMBER"CH6223MEA01";
"B"
$PN"2"15;
"A"
$PN"1"16;
END.
